# BASEBOARD_FAB2 (Tioga Pass) — schematic netlist excerpt (pin names and nets, part order shuffled) for the footprints in the layout excerpt that follows; sources: Cadence DE-HDL packaged netlist, KiCad conversion of Wiwynn_Tioga_Pass_MB.brd

U25W17  TTL1G08  NC7SZ08 IC  pkg SOTLF  page 254
  A(0)  = JTAG_BMC_TRST_N
  B(0)  = BMC_JTAG_SEL_BUF
  Y(0)  = JTAG_BMC_TRST_BUF_N

C3M45  CAP  0.22UF 16V 10% X7R  pkg 0402  page 129 : A = DMI_CPU0_PCH_RX_DN<2> ; B = DMI_CPU0_PCH_RX_C_DN<2>
C3P51  CAP_A  0.1UF 16V 10% X7R  pkg 0402V  page 192 : A = P3V3_STBY ; B = GND

(kicad_pcb
	(version 20260206)
	(generator "pcbnew")
	(generator_version "10.0")
	(general
		(thickness 1.6)
		(legacy_teardrops no)
	)
	(paper "A4")
	(title_block
		(title "Wiwynn_Tioga_Pass_MB.brd")
		(comment 1 "Tioga Pass / footprints 4148-4150 of 4770")
	)
	(layers
		(0 "F.Cu" signal "TOP")
		(4 "In1.Cu" signal "L2GND")
		(6 "In2.Cu" signal "L3")
		(8 "In3.Cu" signal "L4GND")
		(10 "In4.Cu" signal "L5")
		(12 "In5.Cu" signal "L6GND")
		(14 "In6.Cu" signal "L7VCC")
		(16 "In7.Cu" signal "L8VCC")
		(18 "In8.Cu" signal "L9GND")
		(20 "In9.Cu" signal "L10")
		(22 "In10.Cu" signal "L11GND")
		(24 "In11.Cu" signal "L12")
		(26 "In12.Cu" signal "L13GND")
		(2 "B.Cu" signal "BOTTOM")
		(9 "F.Adhes" user "F.Adhesive")
		(11 "B.Adhes" user "B.Adhesive")
		(13 "F.Paste" user "Package Geometry/Pastemask Top")
		(15 "B.Paste" user "Package Geometry/Pastemask Bottom")
		(5 "F.SilkS" user "Ref Des/Silkscreen Top")
		(7 "B.SilkS" user "Ref Des/Silkscreen Bottom")
		(1 "F.Mask" user "Board Geometry/Soldermask Top")
		(3 "B.Mask" user "Board Geometry/Soldermask Bottom")
		(17 "Dwgs.User" user "User.Drawings")
		(19 "Cmts.User" user "User.Comments")
		(21 "Eco1.User" user "User.Eco1")
		(23 "Eco2.User" user "User.Eco2")
		(25 "Edge.Cuts" user "Board Geometry/Outline")
		(27 "Margin" user)
		(31 "F.CrtYd" user "Package Geometry/Place Bound Top")
		(29 "B.CrtYd" user "Package Geometry/Place Bound Bottom")
		(35 "F.Fab" user "Ref Des/Assembly Top")
		(33 "B.Fab" user "Ref Des/Assembly Bottom")
	)
	(footprint ""
		(layer "B.Cu")
		(at 442.468 -157.1498)
		(property "Reference" "U25W17"
			(at 0.14986 2.621788 0)
			(unlocked yes)
			(layer "B.SilkS")
			(effects
				(font
					(size 1.27 0.964946)
					(thickness 0.000001)
				)
				(justify left mirror)
			)
		)
		(property "Value" ""
			(at 0 0 0)
			(layer "B.Fab")
			(effects
				(font
					(size 1.27 1.27)
				)
				(justify mirror)
			)
		)
		(duplicate_pad_numbers_are_jumpers no)
		(fp_circle
			(center 0.4699 -0.8382)
			(end 0.5969 -0.8382)
			(stroke
				(width 0.254)
				(type default)
			)
			(fill no)
			(layer "B.SilkS")
		)
		(fp_poly
			(pts
				(xy -0.21463 -0.450088) (xy -1.56337 -0.450088) (xy -1.56337 1.75006) (xy -0.21463 1.75006)
			)
			(stroke
				(width 0)
				(type default)
			)
			(fill no)
			(layer "B.CrtYd")
		)
		(fp_line
			(start -1.56337 -0.450088)
			(end -1.56337 1.75006)
			(stroke
				(width 0.1)
				(type default)
			)
			(layer "B.Fab")
		)
		(fp_line
			(start -1.56337 1.75006)
			(end -0.21463 1.75006)
			(stroke
				(width 0.1)
				(type default)
			)
			(layer "B.Fab")
		)
		(fp_line
			(start -0.21463 -0.450088)
			(end -1.56337 -0.450088)
			(stroke
				(width 0.1)
				(type default)
			)
			(layer "B.Fab")
		)
		(fp_line
			(start -0.21463 1.75006)
			(end -0.21463 -0.450088)
			(stroke
				(width 0.1)
				(type default)
			)
			(layer "B.Fab")
		)
		(fp_circle
			(center 0.4699 -0.8382)
			(end 0.5969 -0.8382)
			(stroke
				(width 0.254)
				(type default)
			)
			(fill no)
			(layer "B.Fab")
		)
		(pad "1" smd rect
			(at 0 0 180)
			(size 1.016 0.381)
			(layers "B.Cu" "B.Mask" "B.Paste")
			(net "JTAG_BMC_TRST_N")
		)
		(pad "2" smd rect
			(at 0 0.649986 180)
			(size 1.016 0.381)
			(layers "B.Cu" "B.Mask" "B.Paste")
			(net "BMC_JTAG_SEL_BUF")
		)
		(pad "3" smd rect
			(at 0 1.299972 180)
			(size 1.016 0.381)
			(layers "B.Cu" "B.Mask" "B.Paste")
			(net "GND")
		)
		(pad "4" smd rect
			(at -1.778 1.299972 180)
			(size 1.016 0.381)
			(layers "B.Cu" "B.Mask" "B.Paste")
			(net "JTAG_BMC_TRST_BUF_N")
		)
		(pad "5" smd rect
			(at -1.778 0 180)
			(size 1.016 0.381)
			(layers "B.Cu" "B.Mask" "B.Paste")
			(net "P3V3_STBY")
		)
	)
	(footprint ""
		(layer "B.Cu")
		(at 372.980966 -72.678036 180)
		(property "Reference" "C3P51"
			(at 0 0 0)
			(layer "B.SilkS")
			(hide yes)
			(effects
				(font
					(size 1.27 1.27)
				)
				(justify mirror)
			)
		)
		(property "Value" ""
			(at 0 0 0)
			(layer "B.Fab")
			(effects
				(font
					(size 1.27 1.27)
				)
				(justify mirror)
			)
		)
		(duplicate_pad_numbers_are_jumpers no)
		(fp_rect
			(start 0.2794 0.9144)
			(end -0.2794 -0.1143)
			(stroke
				(width 0)
				(type default)
			)
			(fill no)
			(layer "B.CrtYd")
		)
		(fp_line
			(start 0.2794 0.9144)
			(end 0.2794 -0.1143)
			(stroke
				(width 0.1)
				(type default)
			)
			(layer "B.Fab")
		)
		(fp_line
			(start 0.2794 -0.1143)
			(end -0.2794 -0.1143)
			(stroke
				(width 0.1)
				(type default)
			)
			(layer "B.Fab")
		)
		(fp_line
			(start -0.2794 0.9144)
			(end 0.2794 0.9144)
			(stroke
				(width 0.1)
				(type default)
			)
			(layer "B.Fab")
		)
		(fp_line
			(start -0.2794 -0.1143)
			(end -0.2794 0.9144)
			(stroke
				(width 0.1)
				(type default)
			)
			(layer "B.Fab")
		)
		(pad "1" smd custom
			(at 0 0 90)
			(size 0.10414 0.10414)
			(layers "B.Cu" "B.Mask" "B.Paste")
			(net "P3V3_STBY")
			(options
				(clearance outline)
				(anchor circle)
			)
			(primitives
				(gr_poly
					(pts
						(xy -0.20828 -0.08636) (xy -0.20828 0.08636) (xy -0.08636 0.20828) (xy 0.086614 0.20828) (xy 0.20828 0.086614)
						(xy 0.20828 -0.08636) (xy 0.08636 -0.20828) (xy -0.08636 -0.20828)
					)
					(width 0)
					(fill yes)
				)
			)
		)
		(pad "2" smd custom
			(at 0 0.8001 90)
			(size 0.10414 0.10414)
			(layers "B.Cu" "B.Mask" "B.Paste")
			(net "GND")
			(options
				(clearance outline)
				(anchor circle)
			)
			(primitives
				(gr_poly
					(pts
						(xy -0.20828 -0.08636) (xy -0.20828 0.08636) (xy -0.08636 0.20828) (xy 0.086614 0.20828) (xy 0.20828 0.086614)
						(xy 0.20828 -0.08636) (xy 0.08636 -0.20828) (xy -0.08636 -0.20828)
					)
					(width 0)
					(fill yes)
				)
			)
		)
		(zone
			(layer "B.Cu")
			(hatch none 0.5)
			(connect_pads
				(clearance 0)
			)
			(min_thickness 0.25)
			(keepout
				(tracks allowed)
				(vias not_allowed)
				(pads allowed)
				(copperpour not_allowed)
				(footprints allowed)
			)
			(placement
				(enabled no)
				(sheetname "")
			)
			(fill
				(thermal_gap 0.5)
				(thermal_bridge_width 0.5)
				(island_removal_mode 0)
			)
			(polygon
				(pts
					(xy 372.893336 -72.887586) (xy 372.893336 -73.268586) (xy 373.068596 -73.268586) (xy 373.06885 -72.887586)
				)
			)
		)
		(zone
			(layer "B.Cu")
			(hatch none 0.5)
			(connect_pads
				(clearance 0)
			)
			(min_thickness 0.25)
			(keepout
				(tracks not_allowed)
				(vias allowed)
				(pads allowed)
				(copperpour not_allowed)
				(footprints allowed)
			)
			(placement
				(enabled no)
				(sheetname "")
			)
			(fill
				(thermal_gap 0.5)
				(thermal_bridge_width 0.5)
				(island_removal_mode 0)
			)
			(polygon
				(pts
					(xy 372.893336 -72.887586) (xy 372.893336 -73.268586) (xy 373.068596 -73.268586) (xy 373.06885 -72.887586)
				)
			)
		)
	)
	(footprint ""
		(layer "B.Cu")
		(at 365.506 -112.395 -90)
		(property "Reference" "C3M45"
			(at 0 0 90)
			(layer "B.SilkS")
			(hide yes)
			(effects
				(font
					(size 1.27 1.27)
				)
				(justify mirror)
			)
		)
		(property "Value" ""
			(at 0 0 90)
			(layer "B.Fab")
			(effects
				(font
					(size 1.27 1.27)
				)
				(justify mirror)
			)
		)
		(duplicate_pad_numbers_are_jumpers no)
		(fp_poly
			(pts
				(xy -0.3048 -0.1016) (xy -0.3048 0.9906) (xy 0.3048 0.9906) (xy 0.3048 -0.1016)
			)
			(stroke
				(width 0)
				(type default)
			)
			(fill no)
			(layer "B.CrtYd")
		)
		(fp_line
			(start -0.3048 0.9906)
			(end -0.3048 -0.1016)
			(stroke
				(width 0.1)
				(type default)
			)
			(layer "B.Fab")
		)
		(fp_line
			(start 0.3048 0.9906)
			(end -0.3048 0.9906)
			(stroke
				(width 0.1)
				(type default)
			)
			(layer "B.Fab")
		)
		(fp_line
			(start -0.3048 -0.1016)
			(end 0.3048 -0.1016)
			(stroke
				(width 0.1)
				(type default)
			)
			(layer "B.Fab")
		)
		(fp_line
			(start 0.3048 -0.1016)
			(end 0.3048 0.9906)
			(stroke
				(width 0.1)
				(type default)
			)
			(layer "B.Fab")
		)
		(pad "1" smd rect
			(at 0 0 90)
			(size 0.508 0.508)
			(layers "B.Cu" "B.Mask" "B.Paste")
			(net "DMI_CPU0_PCH_RX_DN<2>")
		)
		(pad "2" smd rect
			(at 0 0.889 90)
			(size 0.508 0.508)
			(layers "B.Cu" "B.Mask" "B.Paste")
			(net "DMI_CPU0_PCH_RX_C_DN<2>")
		)
		(zone
			(layer "B.Cu")
			(hatch none 0.5)
			(connect_pads
				(clearance 0)
			)
			(min_thickness 0.25)
			(keepout
				(tracks not_allowed)
				(vias allowed)
				(pads allowed)
				(copperpour not_allowed)
				(footprints allowed)
			)
			(placement
				(enabled no)
				(sheetname "")
			)
			(fill
				(thermal_gap 0.5)
				(thermal_bridge_width 0.5)
				(island_removal_mode 0)
			)
			(polygon
				(pts
					(xy 364.871 -112.141) (xy 364.871 -112.649) (xy 365.252 -112.649) (xy 365.252 -112.141)
				)
			)
		)
		(zone
			(layer "B.Cu")
			(hatch none 0.5)
			(connect_pads
				(clearance 0)
			)
			(min_thickness 0.25)
			(keepout
				(tracks allowed)
				(vias not_allowed)
				(pads allowed)
				(copperpour not_allowed)
				(footprints allowed)
			)
			(placement
				(enabled no)
				(sheetname "")
			)
			(fill
				(thermal_gap 0.5)
				(thermal_bridge_width 0.5)
				(island_removal_mode 0)
			)
			(polygon
				(pts
					(xy 365.252 -112.141) (xy 365.252 -112.649) (xy 364.871 -112.649) (xy 364.871 -112.141)
				)
			)
		)
	)
)
